FILE_TYPE = MULTI_PHYS_TABLE;

PART 'PI4ULS3V304AZMAEX'

{========================================================================================}
:VALUE               | PART_TYPE | MATERIAL | PART_NUMBER    = STANDARD    | LIFECYCLE          | PART_NUMBER   | JEDEC_TYPE         | DESCRIPTION                      | MANUFTR | MANUF_PN            | RD_CMPLS_LVL | CMPLS_LVL | FROM_PJ    | CLASS | DIP_SMD | DATA                        | EE_CHECK_LIST | FP_ECN | PSL | CREATOR | STATUS | MSD | ESD_CDM | ESD_HBM | ESD_MM | PIN_LENGTH_SHORT_PIN | PIN_LENGTH_LONG_PIN | CREATEDAY  ;
{========================================================================================}
 'PI4ULS3V304AZMAEX' | 'SMLF'    | 'IC'     | 'AL000304005'(!) = ''               | ''               | 'AL000304005' |'UQFN12_0-4_2X1-7'| 'IC(12P)PI4ULS3V304AZMAEX(UQFN)' | 'DDS'   | 'PI4ULS3V304AZMAEX' | 'EP(V1)'     | ''        | 'T6G-JOHN' | 'IC'  | ''      | 'DDS_PI4ULS3V304AZMAEX.pdf' | ''            | ''     | ''  | ''      | ''     | ''  | ''      | ''      | ''     | '0 MILS'             | '0 MILS'            | '20211004'
 'PI4ULS3V304AZMAEX' | 'SMLF'    | 'EMPTY'  | 'AL000304005'(!) = ''               | ''               | 'AL000304005' |'UQFN12_0-4_2X1-7'| 'IC(12P)PI4ULS3V304AZMAEX(UQFN)' | 'DDS'   | 'PI4ULS3V304AZMAEX' | 'EP(V1)'     | ''        | 'T6G-JOHN' | 'IC'  | ''      | 'DDS_PI4ULS3V304AZMAEX.pdf' | ''            | ''     | ''  | ''      | ''     | ''  | ''      | ''      | ''     | '0 MILS'             | '0 MILS'            | '20211004'

END_PART

END.

